(kicad_pcb
	(version 20260206)
	(generator "pcbnew")
	(generator_version "10.0")
	(general
		(thickness 1.6)
		(legacy_teardrops no)
	)
	(paper "A4")
	(title_block
		(title "03242023_DA0F0TMBIJ0_F0T_Motherboard_J_brd_V01_OCP.brd")
		(comment 1 "Grand Teton / footprints 3976-3982 of 6105")
	)
	(layers
		(0 "F.Cu" signal "TOP")
		(4 "In1.Cu" signal "GND")
		(6 "In2.Cu" signal "IN1")
		(8 "In3.Cu" signal "GND1")
		(10 "In4.Cu" signal "IN2")
		(12 "In5.Cu" signal "GND2")
		(14 "In6.Cu" signal "IN3")
		(16 "In7.Cu" signal "GND3")
		(18 "In8.Cu" signal "VCC")
		(20 "In9.Cu" signal "VCC1")
		(22 "In10.Cu" signal "GND4")
		(24 "In11.Cu" signal "IN4")
		(26 "In12.Cu" signal "GND5")
		(28 "In13.Cu" signal "IN5")
		(30 "In14.Cu" signal "GND6")
		(32 "In15.Cu" signal "IN6")
		(34 "In16.Cu" signal "GND7")
		(2 "B.Cu" signal "BOTTOM")
		(9 "F.Adhes" user "F.Adhesive")
		(11 "B.Adhes" user "B.Adhesive")
		(13 "F.Paste" user "Package Geometry/Pastemask Top")
		(15 "B.Paste" user "Package Geometry/Pastemask Bottom")
		(5 "F.SilkS" user "Ref Des/Silkscreen Top")
		(7 "B.SilkS" user "Ref Des/Silkscreen Bottom")
		(1 "F.Mask" user "Board Geometry/Soldermask Top")
		(3 "B.Mask" user "Board Geometry/Soldermask Bottom")
		(17 "Dwgs.User" user "User.Drawings")
		(19 "Cmts.User" user "User.Comments")
		(21 "Eco1.User" user "User.Eco1")
		(23 "Eco2.User" user "User.Eco2")
		(25 "Edge.Cuts" user "Board Geometry/Outline")
		(27 "Margin" user)
		(31 "F.CrtYd" user "Package Geometry/Place Bound Top")
		(29 "B.CrtYd" user "Package Geometry/Place Bound Bottom")
		(35 "F.Fab" user "Ref Des/Assembly Top")
		(33 "B.Fab" user "Ref Des/Assembly Bottom")
	)
	(footprint ""
		(layer "F.Cu")
		(at 105.21188 -424.779948 180)
		(property "Reference" "R4181"
			(at 0 0 180)
			(layer "F.SilkS")
			(hide yes)
			(effects
				(font
					(size 1.27 1.27)
				)
			)
		)
		(property "Value" ""
			(at 0 0 180)
			(layer "F.Fab")
			(effects
				(font
					(size 1.27 1.27)
				)
			)
		)
		(duplicate_pad_numbers_are_jumpers no)
		(fp_line
			(start 0.7874 0.4064)
			(end -0.7874 0.4064)
			(stroke
				(width 0.1524)
				(type default)
			)
			(layer "F.SilkS")
		)
		(fp_line
			(start 0.7874 -0.4064)
			(end 0.7874 0.4064)
			(stroke
				(width 0.1524)
				(type default)
			)
			(layer "F.SilkS")
		)
		(fp_line
			(start -0.7874 0.4064)
			(end -0.7874 -0.4064)
			(stroke
				(width 0.1524)
				(type default)
			)
			(layer "F.SilkS")
		)
		(fp_line
			(start -0.7874 -0.4064)
			(end 0.7874 -0.4064)
			(stroke
				(width 0.1524)
				(type default)
			)
			(layer "F.SilkS")
		)
		(fp_line
			(start 0.67945 0.3048)
			(end 0.120396 0.3048)
			(stroke
				(width 0.1)
				(type default)
			)
			(layer "F.Fab")
		)
		(fp_line
			(start 0.67945 -0.3048)
			(end 0.67945 0.3048)
			(stroke
				(width 0.1)
				(type default)
			)
			(layer "F.Fab")
		)
		(fp_line
			(start 0.12065 -0.2794)
			(end 0.12065 -0.3048)
			(stroke
				(width 0.1)
				(type default)
			)
			(layer "F.Fab")
		)
		(fp_line
			(start 0.12065 -0.3048)
			(end 0.67945 -0.3048)
			(stroke
				(width 0.1)
				(type default)
			)
			(layer "F.Fab")
		)
		(fp_line
			(start 0.120396 0.3048)
			(end 0.120396 0.2794)
			(stroke
				(width 0.1)
				(type default)
			)
			(layer "F.Fab")
		)
		(fp_line
			(start 0.120396 0.2794)
			(end -0.12065 0.2794)
			(stroke
				(width 0.1)
				(type default)
			)
			(layer "F.Fab")
		)
		(fp_line
			(start -0.12065 0.3048)
			(end -0.67945 0.3048)
			(stroke
				(width 0.1)
				(type default)
			)
			(layer "F.Fab")
		)
		(fp_line
			(start -0.12065 0.2794)
			(end -0.12065 0.3048)
			(stroke
				(width 0.1)
				(type default)
			)
			(layer "F.Fab")
		)
		(fp_line
			(start -0.12065 -0.2794)
			(end 0.12065 -0.2794)
			(stroke
				(width 0.1)
				(type default)
			)
			(layer "F.Fab")
		)
		(fp_line
			(start -0.12065 -0.305054)
			(end -0.12065 -0.2794)
			(stroke
				(width 0.1)
				(type default)
			)
			(layer "F.Fab")
		)
		(fp_line
			(start -0.67945 0.3048)
			(end -0.67945 -0.305054)
			(stroke
				(width 0.1)
				(type default)
			)
			(layer "F.Fab")
		)
		(fp_line
			(start -0.67945 -0.305054)
			(end -0.12065 -0.305054)
			(stroke
				(width 0.1)
				(type default)
			)
			(layer "F.Fab")
		)
		(pad "1" smd circle
			(at -0.40005 0 180)
			(size 0 0)
			(layers "F.Cu" "F.Mask" "F.Paste")
			(net "SMB_LM75_2_3V3AUX_SDA")
		)
		(pad "2" smd circle
			(at 0.40005 0 180)
			(size 0 0)
			(layers "F.Cu" "F.Mask" "F.Paste")
			(net "SMB_LM75_2_3V3AUX_SDA_R1")
		)
	)
	(footprint ""
		(layer "F.Cu")
		(at 435.43728 -179.390548 90)
		(property "Reference" "PR4271"
			(at 0 0 90)
			(layer "F.SilkS")
			(hide yes)
			(effects
				(font
					(size 1.27 1.27)
				)
			)
		)
		(property "Value" ""
			(at 0 0 90)
			(layer "F.Fab")
			(effects
				(font
					(size 1.27 1.27)
				)
			)
		)
		(duplicate_pad_numbers_are_jumpers no)
		(fp_line
			(start 0.7874 -0.4064)
			(end 0.7874 0.4064)
			(stroke
				(width 0.1524)
				(type default)
			)
			(layer "F.SilkS")
		)
		(fp_line
			(start -0.7874 -0.4064)
			(end 0.7874 -0.4064)
			(stroke
				(width 0.1524)
				(type default)
			)
			(layer "F.SilkS")
		)
		(fp_line
			(start 0.7874 0.4064)
			(end -0.7874 0.4064)
			(stroke
				(width 0.1524)
				(type default)
			)
			(layer "F.SilkS")
		)
		(fp_line
			(start -0.7874 0.4064)
			(end -0.7874 -0.4064)
			(stroke
				(width 0.1524)
				(type default)
			)
			(layer "F.SilkS")
		)
		(fp_line
			(start -0.12065 -0.305054)
			(end -0.12065 -0.2794)
			(stroke
				(width 0.1)
				(type default)
			)
			(layer "F.Fab")
		)
		(fp_line
			(start -0.67945 -0.305054)
			(end -0.12065 -0.305054)
			(stroke
				(width 0.1)
				(type default)
			)
			(layer "F.Fab")
		)
		(fp_line
			(start 0.67945 -0.3048)
			(end 0.67945 0.3048)
			(stroke
				(width 0.1)
				(type default)
			)
			(layer "F.Fab")
		)
		(fp_line
			(start 0.12065 -0.3048)
			(end 0.67945 -0.3048)
			(stroke
				(width 0.1)
				(type default)
			)
			(layer "F.Fab")
		)
		(fp_line
			(start 0.12065 -0.2794)
			(end 0.12065 -0.3048)
			(stroke
				(width 0.1)
				(type default)
			)
			(layer "F.Fab")
		)
		(fp_line
			(start -0.12065 -0.2794)
			(end 0.12065 -0.2794)
			(stroke
				(width 0.1)
				(type default)
			)
			(layer "F.Fab")
		)
		(fp_line
			(start 0.120396 0.2794)
			(end -0.12065 0.2794)
			(stroke
				(width 0.1)
				(type default)
			)
			(layer "F.Fab")
		)
		(fp_line
			(start -0.12065 0.2794)
			(end -0.12065 0.3048)
			(stroke
				(width 0.1)
				(type default)
			)
			(layer "F.Fab")
		)
		(fp_line
			(start 0.67945 0.3048)
			(end 0.120396 0.3048)
			(stroke
				(width 0.1)
				(type default)
			)
			(layer "F.Fab")
		)
		(fp_line
			(start 0.120396 0.3048)
			(end 0.120396 0.2794)
			(stroke
				(width 0.1)
				(type default)
			)
			(layer "F.Fab")
		)
		(fp_line
			(start -0.12065 0.3048)
			(end -0.67945 0.3048)
			(stroke
				(width 0.1)
				(type default)
			)
			(layer "F.Fab")
		)
		(fp_line
			(start -0.67945 0.3048)
			(end -0.67945 -0.305054)
			(stroke
				(width 0.1)
				(type default)
			)
			(layer "F.Fab")
		)
		(pad "1" smd circle
			(at -0.40005 0 90)
			(size 0 0)
			(layers "F.Cu" "F.Mask" "F.Paste")
			(net "SW_PVNN_MAIN_CPU0_BST")
		)
		(pad "2" smd circle
			(at 0.40005 0 90)
			(size 0 0)
			(layers "F.Cu" "F.Mask" "F.Paste")
			(net "SW_PVNN_MAIN_CPU0_BST_R")
		)
	)
	(footprint ""
		(layer "F.Cu")
		(at 211.99729 -71.13143)
		(property "Reference" "R1354"
			(at 0 0 0)
			(layer "F.SilkS")
			(hide yes)
			(effects
				(font
					(size 1.27 1.27)
				)
			)
		)
		(property "Value" ""
			(at 0 0 0)
			(layer "F.Fab")
			(effects
				(font
					(size 1.27 1.27)
				)
			)
		)
		(duplicate_pad_numbers_are_jumpers no)
		(fp_line
			(start -0.7874 -0.4064)
			(end 0.7874 -0.4064)
			(stroke
				(width 0.1524)
				(type default)
			)
			(layer "F.SilkS")
		)
		(fp_line
			(start -0.7874 0.4064)
			(end -0.7874 -0.4064)
			(stroke
				(width 0.1524)
				(type default)
			)
			(layer "F.SilkS")
		)
		(fp_line
			(start 0.7874 -0.4064)
			(end 0.7874 0.4064)
			(stroke
				(width 0.1524)
				(type default)
			)
			(layer "F.SilkS")
		)
		(fp_line
			(start 0.7874 0.4064)
			(end -0.7874 0.4064)
			(stroke
				(width 0.1524)
				(type default)
			)
			(layer "F.SilkS")
		)
		(fp_line
			(start -0.67945 -0.305054)
			(end -0.12065 -0.305054)
			(stroke
				(width 0.1)
				(type default)
			)
			(layer "F.Fab")
		)
		(fp_line
			(start -0.67945 0.3048)
			(end -0.67945 -0.305054)
			(stroke
				(width 0.1)
				(type default)
			)
			(layer "F.Fab")
		)
		(fp_line
			(start -0.12065 -0.305054)
			(end -0.12065 -0.2794)
			(stroke
				(width 0.1)
				(type default)
			)
			(layer "F.Fab")
		)
		(fp_line
			(start -0.12065 -0.2794)
			(end 0.12065 -0.2794)
			(stroke
				(width 0.1)
				(type default)
			)
			(layer "F.Fab")
		)
		(fp_line
			(start -0.12065 0.2794)
			(end -0.12065 0.3048)
			(stroke
				(width 0.1)
				(type default)
			)
			(layer "F.Fab")
		)
		(fp_line
			(start -0.12065 0.3048)
			(end -0.67945 0.3048)
			(stroke
				(width 0.1)
				(type default)
			)
			(layer "F.Fab")
		)
		(fp_line
			(start 0.120396 0.2794)
			(end -0.12065 0.2794)
			(stroke
				(width 0.1)
				(type default)
			)
			(layer "F.Fab")
		)
		(fp_line
			(start 0.120396 0.3048)
			(end 0.120396 0.2794)
			(stroke
				(width 0.1)
				(type default)
			)
			(layer "F.Fab")
		)
		(fp_line
			(start 0.12065 -0.3048)
			(end 0.67945 -0.3048)
			(stroke
				(width 0.1)
				(type default)
			)
			(layer "F.Fab")
		)
		(fp_line
			(start 0.12065 -0.2794)
			(end 0.12065 -0.3048)
			(stroke
				(width 0.1)
				(type default)
			)
			(layer "F.Fab")
		)
		(fp_line
			(start 0.67945 -0.3048)
			(end 0.67945 0.3048)
			(stroke
				(width 0.1)
				(type default)
			)
			(layer "F.Fab")
		)
		(fp_line
			(start 0.67945 0.3048)
			(end 0.120396 0.3048)
			(stroke
				(width 0.1)
				(type default)
			)
			(layer "F.Fab")
		)
		(pad "1" smd circle
			(at -0.40005 0)
			(size 0 0)
			(layers "F.Cu" "F.Mask" "F.Paste")
			(net "RMII_BMC_OCP_TXD_0")
		)
		(pad "2" smd circle
			(at 0.40005 0)
			(size 0 0)
			(layers "F.Cu" "F.Mask" "F.Paste")
			(net "GND")
		)
	)
	(footprint ""
		(layer "F.Cu")
		(at 374.03151 -413.918908 90)
		(property "Reference" "R4515"
			(at 0 0 90)
			(layer "F.SilkS")
			(hide yes)
			(effects
				(font
					(size 1.27 1.27)
				)
			)
		)
		(property "Value" ""
			(at 0 0 90)
			(layer "F.Fab")
			(effects
				(font
					(size 1.27 1.27)
				)
			)
		)
		(duplicate_pad_numbers_are_jumpers no)
		(fp_line
			(start 0.7874 -0.4064)
			(end 0.7874 0.4064)
			(stroke
				(width 0.1524)
				(type default)
			)
			(layer "F.SilkS")
		)
		(fp_line
			(start -0.7874 -0.4064)
			(end 0.7874 -0.4064)
			(stroke
				(width 0.1524)
				(type default)
			)
			(layer "F.SilkS")
		)
		(fp_line
			(start 0.7874 0.4064)
			(end -0.7874 0.4064)
			(stroke
				(width 0.1524)
				(type default)
			)
			(layer "F.SilkS")
		)
		(fp_line
			(start -0.7874 0.4064)
			(end -0.7874 -0.4064)
			(stroke
				(width 0.1524)
				(type default)
			)
			(layer "F.SilkS")
		)
		(fp_line
			(start -0.12065 -0.305054)
			(end -0.12065 -0.2794)
			(stroke
				(width 0.1)
				(type default)
			)
			(layer "F.Fab")
		)
		(fp_line
			(start -0.67945 -0.305054)
			(end -0.12065 -0.305054)
			(stroke
				(width 0.1)
				(type default)
			)
			(layer "F.Fab")
		)
		(fp_line
			(start 0.67945 -0.3048)
			(end 0.67945 0.3048)
			(stroke
				(width 0.1)
				(type default)
			)
			(layer "F.Fab")
		)
		(fp_line
			(start 0.12065 -0.3048)
			(end 0.67945 -0.3048)
			(stroke
				(width 0.1)
				(type default)
			)
			(layer "F.Fab")
		)
		(fp_line
			(start 0.12065 -0.2794)
			(end 0.12065 -0.3048)
			(stroke
				(width 0.1)
				(type default)
			)
			(layer "F.Fab")
		)
		(fp_line
			(start -0.12065 -0.2794)
			(end 0.12065 -0.2794)
			(stroke
				(width 0.1)
				(type default)
			)
			(layer "F.Fab")
		)
		(fp_line
			(start 0.120396 0.2794)
			(end -0.12065 0.2794)
			(stroke
				(width 0.1)
				(type default)
			)
			(layer "F.Fab")
		)
		(fp_line
			(start -0.12065 0.2794)
			(end -0.12065 0.3048)
			(stroke
				(width 0.1)
				(type default)
			)
			(layer "F.Fab")
		)
		(fp_line
			(start 0.67945 0.3048)
			(end 0.120396 0.3048)
			(stroke
				(width 0.1)
				(type default)
			)
			(layer "F.Fab")
		)
		(fp_line
			(start 0.120396 0.3048)
			(end 0.120396 0.2794)
			(stroke
				(width 0.1)
				(type default)
			)
			(layer "F.Fab")
		)
		(fp_line
			(start -0.12065 0.3048)
			(end -0.67945 0.3048)
			(stroke
				(width 0.1)
				(type default)
			)
			(layer "F.Fab")
		)
		(fp_line
			(start -0.67945 0.3048)
			(end -0.67945 -0.305054)
			(stroke
				(width 0.1)
				(type default)
			)
			(layer "F.Fab")
		)
		(pad "1" smd circle
			(at -0.40005 0 90)
			(size 0 0)
			(layers "F.Cu" "F.Mask" "F.Paste")
			(net "P3V3_AUX")
		)
		(pad "2" smd circle
			(at 0.40005 0 90)
			(size 0 0)
			(layers "F.Cu" "F.Mask" "F.Paste")
			(net "UART_BMC_BIC_RX")
		)
	)
	(footprint ""
		(layer "F.Cu")
		(at 483.281228 -343.22893)
		(property "Reference" "DB7"
			(at 2.576068 2.020062 90)
			(unlocked yes)
			(layer "F.SilkS")
			(effects
				(font
					(size 0.7874 0.5842)
					(thickness 0.1524)
				)
				(justify left)
			)
		)
		(property "Value" ""
			(at 0 0 0)
			(layer "F.Fab")
			(effects
				(font
					(size 1.27 1.27)
				)
			)
		)
		(duplicate_pad_numbers_are_jumpers no)
		(fp_line
			(start -3.330702 -4.771136)
			(end 3.330702 -4.771136)
			(stroke
				(width 0.1524)
				(type default)
			)
			(layer "F.SilkS")
		)
		(fp_line
			(start 0 4.011168)
			(end -3.330702 -4.771136)
			(stroke
				(width 0.1524)
				(type default)
			)
			(layer "F.SilkS")
		)
		(fp_line
			(start 3.330702 -4.771136)
			(end 0 4.011168)
			(stroke
				(width 0.1524)
				(type default)
			)
			(layer "F.SilkS")
		)
		(fp_line
			(start -3.330702 -4.771136)
			(end 3.330702 -4.771136)
			(stroke
				(width 0.1)
				(type default)
			)
			(layer "F.Fab")
		)
		(fp_line
			(start 0 4.011168)
			(end -3.330702 -4.771136)
			(stroke
				(width 0.1)
				(type default)
			)
			(layer "F.Fab")
		)
		(fp_line
			(start 3.330702 -4.771136)
			(end 0 4.011168)
			(stroke
				(width 0.1)
				(type default)
			)
			(layer "F.Fab")
		)
		(pad "1" thru_hole circle
			(at 0 0)
			(size 2.159 2.159)
			(drill 1.7018)
			(layers "*.Cu" "*.Mask")
			(remove_unused_layers no)
			(net "T1_GND")
			(clearance 0.0254)
			(thermal_gap 0.0254)
		)
		(pad "2" thru_hole circle
			(at -1.27 -3.348736)
			(size 2.159 2.159)
			(drill 1.7018)
			(layers "*.Cu" "*.Mask")
			(remove_unused_layers no)
			(net "TDR_SE_50_OHM_TOP")
			(clearance 0.0254)
			(thermal_gap 0.0254)
		)
		(pad "3" thru_hole circle
			(at 1.27 -3.348736)
			(size 2.159 2.159)
			(drill 1.7018)
			(layers "*.Cu" "*.Mask")
			(remove_unused_layers no)
			(net "TDR_SE_50_OHM_TOP")
			(clearance 0.0254)
			(thermal_gap 0.0254)
		)
	)
	(footprint ""
		(layer "F.Cu")
		(at 340.033864 -354.332032 -90)
		(property "Reference" "PL15"
			(at -8.8011 1.901698 0)
			(unlocked yes)
			(layer "F.SilkS")
			(effects
				(font
					(size 0.7874 0.5842)
					(thickness 0.1524)
				)
				(justify left)
			)
		)
		(property "Value" ""
			(at 0 0 270)
			(layer "F.Fab")
			(effects
				(font
					(size 1.27 1.27)
				)
			)
		)
		(duplicate_pad_numbers_are_jumpers no)
		(fp_line
			(start -4.99999 4.150106)
			(end 4.99999 4.150106)
			(stroke
				(width 0.1524)
				(type default)
			)
			(layer "F.SilkS")
		)
		(fp_line
			(start 4.99999 4.150106)
			(end 4.99999 2.4892)
			(stroke
				(width 0.1524)
				(type default)
			)
			(layer "F.SilkS")
		)
		(fp_line
			(start -4.99999 2.4892)
			(end -4.99999 4.150106)
			(stroke
				(width 0.1524)
				(type default)
			)
			(layer "F.SilkS")
		)
		(fp_line
			(start 4.99999 -2.4892)
			(end 4.99999 -4.150106)
			(stroke
				(width 0.1524)
				(type default)
			)
			(layer "F.SilkS")
		)
		(fp_line
			(start -4.99999 -4.150106)
			(end -4.99999 -2.4892)
			(stroke
				(width 0.1524)
				(type default)
			)
			(layer "F.SilkS")
		)
		(fp_line
			(start 4.99999 -4.150106)
			(end -4.99999 -4.150106)
			(stroke
				(width 0.1524)
				(type default)
			)
			(layer "F.SilkS")
		)
		(fp_line
			(start -4.99999 4.150106)
			(end 4.99999 4.150106)
			(stroke
				(width 0.1)
				(type default)
			)
			(layer "F.Fab")
		)
		(fp_line
			(start 4.99999 4.150106)
			(end 4.99999 -4.150106)
			(stroke
				(width 0.1)
				(type default)
			)
			(layer "F.Fab")
		)
		(fp_line
			(start -4.99999 -4.150106)
			(end -4.99999 4.150106)
			(stroke
				(width 0.1)
				(type default)
			)
			(layer "F.Fab")
		)
		(fp_line
			(start 4.99999 -4.150106)
			(end -4.99999 -4.150106)
			(stroke
				(width 0.1)
				(type default)
			)
			(layer "F.Fab")
		)
		(pad "1" smd rect
			(at -4.174998 0 270)
			(size 2.159 4.699)
			(layers "F.Cu" "F.Mask" "F.Paste")
			(net "P12V_AUX")
		)
		(pad "2" smd rect
			(at 4.174998 0 270)
			(size 2.159 4.699)
			(layers "F.Cu" "F.Mask" "F.Paste")
			(net "SW_P12V_PVCCIN_CPU0_FLT")
		)
	)
	(footprint ""
		(layer "F.Cu")
		(at 285.211266 -365.251746 90)
		(property "Reference" "PC1172"
			(at 0 0 90)
			(layer "F.SilkS")
			(hide yes)
			(effects
				(font
					(size 1.27 1.27)
				)
			)
		)
		(property "Value" ""
			(at 0 0 90)
			(layer "F.Fab")
			(effects
				(font
					(size 1.27 1.27)
				)
			)
		)
		(duplicate_pad_numbers_are_jumpers no)
		(fp_line
			(start 0.7874 -0.4064)
			(end 0.7874 0.4064)
			(stroke
				(width 0.1524)
				(type default)
			)
			(layer "F.SilkS")
		)
		(fp_line
			(start -0.7874 -0.4064)
			(end 0.7874 -0.4064)
			(stroke
				(width 0.1524)
				(type default)
			)
			(layer "F.SilkS")
		)
		(fp_line
			(start 0.7874 0.4064)
			(end -0.7874 0.4064)
			(stroke
				(width 0.1524)
				(type default)
			)
			(layer "F.SilkS")
		)
		(fp_line
			(start -0.7874 0.4064)
			(end -0.7874 -0.4064)
			(stroke
				(width 0.1524)
				(type default)
			)
			(layer "F.SilkS")
		)
		(fp_line
			(start -0.12065 -0.305054)
			(end -0.12065 -0.2794)
			(stroke
				(width 0.1)
				(type default)
			)
			(layer "F.Fab")
		)
		(fp_line
			(start -0.67945 -0.305054)
			(end -0.12065 -0.305054)
			(stroke
				(width 0.1)
				(type default)
			)
			(layer "F.Fab")
		)
		(fp_line
			(start 0.67945 -0.3048)
			(end 0.67945 0.3048)
			(stroke
				(width 0.1)
				(type default)
			)
			(layer "F.Fab")
		)
		(fp_line
			(start 0.12065 -0.3048)
			(end 0.67945 -0.3048)
			(stroke
				(width 0.1)
				(type default)
			)
			(layer "F.Fab")
		)
		(fp_line
			(start 0.12065 -0.2794)
			(end 0.12065 -0.3048)
			(stroke
				(width 0.1)
				(type default)
			)
			(layer "F.Fab")
		)
		(fp_line
			(start -0.12065 -0.2794)
			(end 0.12065 -0.2794)
			(stroke
				(width 0.1)
				(type default)
			)
			(layer "F.Fab")
		)
		(fp_line
			(start 0.120396 0.2794)
			(end -0.12065 0.2794)
			(stroke
				(width 0.1)
				(type default)
			)
			(layer "F.Fab")
		)
		(fp_line
			(start -0.12065 0.2794)
			(end -0.12065 0.3048)
			(stroke
				(width 0.1)
				(type default)
			)
			(layer "F.Fab")
		)
		(fp_line
			(start 0.67945 0.3048)
			(end 0.120396 0.3048)
			(stroke
				(width 0.1)
				(type default)
			)
			(layer "F.Fab")
		)
		(fp_line
			(start 0.120396 0.3048)
			(end 0.120396 0.2794)
			(stroke
				(width 0.1)
				(type default)
			)
			(layer "F.Fab")
		)
		(fp_line
			(start -0.12065 0.3048)
			(end -0.67945 0.3048)
			(stroke
				(width 0.1)
				(type default)
			)
			(layer "F.Fab")
		)
		(fp_line
			(start -0.67945 0.3048)
			(end -0.67945 -0.305054)
			(stroke
				(width 0.1)
				(type default)
			)
			(layer "F.Fab")
		)
		(pad "1" smd circle
			(at -0.40005 0 90)
			(size 0 0)
			(layers "F.Cu" "F.Mask" "F.Paste")
			(net "PVCCFA_EHV_FIVRA_CPU0_VDD4")
		)
		(pad "2" smd circle
			(at 0.40005 0 90)
			(size 0 0)
			(layers "F.Cu" "F.Mask" "F.Paste")
			(net "GND")
		)
	)
)
